(kicad_pcb
	(version 20241229)
	(generator "pcbnew")
	(generator_version "9.0")
	(general
		(thickness 1.63)
		(legacy_teardrops no)
	)
	(paper "A4")
	(title_block
		(title "CM4 Baseboard")
		(date "2026-01-05")
		(rev "1.1.1")
		(company "Antmicro Ltd")
		(comment 1 "www.antmicro.com")
		(comment 9 "footprints 408-412 of 506")
	)
	(layers
		(0 "F.Cu" signal)
		(4 "In1.Cu" power)
		(6 "In2.Cu" power)
		(8 "In3.Cu" signal)
		(10 "In4.Cu" signal)
		(2 "B.Cu" signal)
		(9 "F.Adhes" user "F.Adhesive")
		(11 "B.Adhes" user "B.Adhesive")
		(13 "F.Paste" user)
		(15 "B.Paste" user)
		(5 "F.SilkS" user "F.Silkscreen")
		(7 "B.SilkS" user "B.Silkscreen")
		(1 "F.Mask" user)
		(3 "B.Mask" user)
		(17 "Dwgs.User" user "User.Drawings")
		(19 "Cmts.User" user "User.Comments")
		(21 "Eco1.User" user "User.Eco1")
		(23 "Eco2.User" user "User.Eco2")
		(25 "Edge.Cuts" user)
		(27 "Margin" user)
		(31 "F.CrtYd" user "F.Courtyard")
		(29 "B.CrtYd" user "B.Courtyard")
		(35 "F.Fab" user)
		(33 "B.Fab" user)
	)
	(footprint "antmicro-footprints:SOD-123FL"
		(layer "B.Cu")
		(at 40.467962 154.7865 180)
		(property "Reference" "D303"
			(at -2.53 1.3 0)
			(layer "B.SilkS")
			(effects
				(font
					(size 0.7 0.7)
					(thickness 0.15)
				)
				(justify left bottom mirror)
			)
		)
		(property "Value" "SMF4L15A"
			(at 0 -1.967 0)
			(layer "B.Fab")
			(effects
				(font
					(size 0.7 0.7)
					(thickness 0.15)
				)
				(justify left bottom mirror)
			)
		)
		(property "Datasheet" "https://www.littelfuse.com/media?resourcetype=datasheets&itemid=d2ba8fab-1de3-4176-8530-f36ecb0b8799&filename=smf4l"
			(at 0 0 180)
			(layer "B.Fab")
			(hide yes)
			(effects
				(font
					(size 1.27 1.27)
					(thickness 0.15)
				)
			)
		)
		(property "Manufacturer" "Littelfuse"
			(at 0 0 180)
			(unlocked yes)
			(layer "B.Fab")
			(hide yes)
			(effects
				(font
					(size 1 1)
					(thickness 0.15)
				)
				(justify mirror)
			)
		)
		(property "MPN" "SMF4L15A"
			(at 0 0 180)
			(unlocked yes)
			(layer "B.Fab")
			(hide yes)
			(effects
				(font
					(size 1 1)
					(thickness 0.15)
				)
				(justify mirror)
			)
		)
		(property "Author" "Antmicro"
			(at 0 0 180)
			(unlocked yes)
			(layer "B.Fab")
			(hide yes)
			(effects
				(font
					(size 1 1)
					(thickness 0.15)
				)
				(justify mirror)
			)
		)
		(property "License" "Apache-2.0"
			(at 0 0 180)
			(unlocked yes)
			(layer "B.Fab")
			(hide yes)
			(effects
				(font
					(size 1 1)
					(thickness 0.15)
				)
				(justify mirror)
			)
		)
		(sheetname "/Supply/")
		(sheetfile "supply.kicad_sch")
		(attr smd)
		(fp_line
			(start 0 1.1)
			(end -2.3 1.1)
			(stroke
				(width 0.15)
				(type solid)
			)
			(layer "B.SilkS")
		)
		(fp_line
			(start -2.3 1.1)
			(end -2.3 -1.1)
			(stroke
				(width 0.15)
				(type solid)
			)
			(layer "B.SilkS")
		)
		(fp_line
			(start -2.3 -1.1)
			(end 0 -1.1)
			(stroke
				(width 0.15)
				(type solid)
			)
			(layer "B.SilkS")
		)
		(fp_rect
			(start -2.35 1.125)
			(end 2.35 -1.125)
			(stroke
				(width 0.05)
				(type solid)
			)
			(fill no)
			(layer "B.CrtYd")
		)
		(fp_rect
			(start -0.775 0.875)
			(end -0.525 -0.875)
			(stroke
				(width 0.15)
				(type solid)
			)
			(fill yes)
			(layer "B.Fab")
		)
		(fp_rect
			(start -1.825 0.875)
			(end 1.824 -0.873)
			(stroke
				(width 0.15)
				(type solid)
			)
			(fill no)
			(layer "B.Fab")
		)
		(fp_text user "Author: Antmicro"
			(at -2.406 -5.168 0)
			(layer "B.Fab")
			(effects
				(font
					(size 0.7 0.7)
					(thickness 0.15)
				)
				(justify left bottom mirror)
			)
		)
		(fp_text user "License: Apache-2.0"
			(at -2.406 -6.368 0)
			(layer "B.Fab")
			(effects
				(font
					(size 0.7 0.7)
					(thickness 0.15)
				)
				(justify left bottom mirror)
			)
		)
		(fp_text user "${REFERENCE}"
			(at -2.406 -3.967 0)
			(layer "B.Fab")
			(effects
				(font
					(size 0.7 0.7)
					(thickness 0.15)
				)
				(justify left bottom mirror)
			)
		)
		(pad "1" smd roundrect
			(at -1.43 0 180)
			(size 1.34 1.8)
			(layers "B.Cu" "B.Mask" "B.Paste")
			(roundrect_rratio 0.14)
			(net 43 "VCC")
			(pinfunction "C")
			(pintype "passive")
		)
		(pad "2" smd roundrect
			(at 1.429 0 180)
			(size 1.34 1.8)
			(layers "B.Cu" "B.Mask" "B.Paste")
			(roundrect_rratio 0.14)
			(net 3 "GND")
			(pinfunction "A")
			(pintype "passive")
		)
	)
	(footprint "antmicro-footprints:C_0402_1005Metric"
		(layer "B.Cu")
		(at 71.942962 129.9365 180)
		(descr "Capacitor SMD 0402")
		(tags "capacitor SMD 0402")
		(property "Reference" "C403"
			(at -2.005 -2.3 0)
			(layer "B.SilkS")
			(effects
				(font
					(size 0.7 0.7)
					(thickness 0.15)
				)
				(justify left bottom mirror)
			)
		)
		(property "Value" "C_100n_0402"
			(at -1.022927 -2.155213 0)
			(layer "B.Fab")
			(effects
				(font
					(size 0.7 0.7)
					(thickness 0.15)
				)
				(justify left bottom mirror)
			)
		)
		(property "Datasheet" "https://www.murata.com/products/productdetail?partno=GRM155R61H104KE14%23"
			(at 0 0 180)
			(layer "B.Fab")
			(hide yes)
			(effects
				(font
					(size 1.27 1.27)
					(thickness 0.15)
				)
			)
		)
		(property "Manufacturer" "Murata"
			(at 0 0 180)
			(unlocked yes)
			(layer "B.Fab")
			(hide yes)
			(effects
				(font
					(size 1 1)
					(thickness 0.15)
				)
				(justify mirror)
			)
		)
		(property "MPN" "GRM155R61H104KE14D"
			(at 0 0 180)
			(unlocked yes)
			(layer "B.Fab")
			(hide yes)
			(effects
				(font
					(size 1 1)
					(thickness 0.15)
				)
				(justify mirror)
			)
		)
		(property "Val" "100n"
			(at 0 0 180)
			(unlocked yes)
			(layer "B.Fab")
			(hide yes)
			(effects
				(font
					(size 1 1)
					(thickness 0.15)
				)
				(justify mirror)
			)
		)
		(property "License" "Apache-2.0"
			(at 0 0 180)
			(unlocked yes)
			(layer "B.Fab")
			(hide yes)
			(effects
				(font
					(size 1 1)
					(thickness 0.15)
				)
				(justify mirror)
			)
		)
		(property "Author" "Antmicro"
			(at 0 0 180)
			(unlocked yes)
			(layer "B.Fab")
			(hide yes)
			(effects
				(font
					(size 1 1)
					(thickness 0.15)
				)
				(justify mirror)
			)
		)
		(property "Voltage" "50V"
			(at 0 0 180)
			(unlocked yes)
			(layer "B.Fab")
			(hide yes)
			(effects
				(font
					(size 1 1)
					(thickness 0.15)
				)
				(justify mirror)
			)
		)
		(property "Dielectric" "X5R"
			(at 0 0 180)
			(unlocked yes)
			(layer "B.Fab")
			(hide yes)
			(effects
				(font
					(size 1 1)
					(thickness 0.15)
				)
				(justify mirror)
			)
		)
		(sheetname "/Ethernet/")
		(sheetfile "ethernet.kicad_sch")
		(attr smd)
		(fp_rect
			(start -0.925 0.47)
			(end 0.925 -0.47)
			(stroke
				(width 0.05)
				(type default)
			)
			(fill no)
			(layer "B.CrtYd")
		)
		(fp_line
			(start 0.504 0.25)
			(end 0.504 -0.248)
			(stroke
				(width 0.15)
				(type solid)
			)
			(layer "B.Fab")
		)
		(fp_line
			(start 0.504 -0.248)
			(end -0.494 -0.248)
			(stroke
				(width 0.15)
				(type solid)
			)
			(layer "B.Fab")
		)
		(fp_line
			(start -0.494 0.25)
			(end 0.504 0.25)
			(stroke
				(width 0.15)
				(type solid)
			)
			(layer "B.Fab")
		)
		(fp_line
			(start -0.494 -0.248)
			(end -0.494 0.25)
			(stroke
				(width 0.15)
				(type solid)
			)
			(layer "B.Fab")
		)
		(fp_text user "Author: Antmicro"
			(at -0.939 -3.399 0)
			(layer "B.Fab")
			(effects
				(font
					(size 0.7 0.7)
					(thickness 0.15)
				)
				(justify left bottom mirror)
			)
		)
		(fp_text user "${REFERENCE}"
			(at -0.939 -4.599 0)
			(layer "B.Fab")
			(effects
				(font
					(size 0.7 0.7)
					(thickness 0.15)
				)
				(justify left bottom mirror)
			)
		)
		(fp_text user "License: Apache-2.0"
			(at -0.939 -5.799 0)
			(layer "B.Fab")
			(effects
				(font
					(size 0.7 0.7)
					(thickness 0.15)
				)
				(justify left bottom mirror)
			)
		)
		(pad "1" smd roundrect
			(at -0.48 0 180)
			(size 0.59 0.64)
			(layers "B.Cu" "B.Mask" "B.Paste")
			(roundrect_rratio 0.25)
			(net 92 "Net-(C403-Pad1)")
			(pintype "passive")
		)
		(pad "2" smd roundrect
			(at 0.48 0 180)
			(size 0.59 0.64)
			(layers "B.Cu" "B.Mask" "B.Paste")
			(roundrect_rratio 0.25)
			(net 3 "GND")
			(pintype "passive")
		)
	)
	(footprint "antmicro-footprints:R_0402_1005Metric"
		(layer "B.Cu")
		(at 76.45 152.67 90)
		(descr "Resistor SMD 0402")
		(tags "resistor SMD 0402")
		(property "Reference" "R263"
			(at -3.73 0.5 90)
			(layer "B.SilkS")
			(effects
				(font
					(size 0.7 0.7)
					(thickness 0.15)
				)
				(justify right bottom mirror)
			)
		)
		(property "Value" "R_100k_0402"
			(at -1.011843 -1.772047 90)
			(layer "B.Fab")
			(effects
				(font
					(size 0.7 0.7)
					(thickness 0.15)
				)
				(justify right bottom mirror)
			)
		)
		(property "Datasheet" "https://www.bourns.com/docs/product-datasheets/cr.pdf"
			(at 0 0 90)
			(layer "B.Fab")
			(hide yes)
			(effects
				(font
					(size 1.27 1.27)
					(thickness 0.15)
				)
			)
		)
		(property "Manufacturer" "Bourns"
			(at 0 0 90)
			(unlocked yes)
			(layer "B.Fab")
			(hide yes)
			(effects
				(font
					(size 1 1)
					(thickness 0.15)
				)
				(justify mirror)
			)
		)
		(property "MPN" "CR0402-FX-1003GLF"
			(at 0 0 90)
			(unlocked yes)
			(layer "B.Fab")
			(hide yes)
			(effects
				(font
					(size 1 1)
					(thickness 0.15)
				)
				(justify mirror)
			)
		)
		(property "Val" "100k"
			(at 0 0 90)
			(unlocked yes)
			(layer "B.Fab")
			(hide yes)
			(effects
				(font
					(size 1 1)
					(thickness 0.15)
				)
				(justify mirror)
			)
		)
		(property "License" "Apache-2.0"
			(at 0 0 90)
			(unlocked yes)
			(layer "B.Fab")
			(hide yes)
			(effects
				(font
					(size 1 1)
					(thickness 0.15)
				)
				(justify mirror)
			)
		)
		(property "Author" "Antmicro"
			(at 0 0 90)
			(unlocked yes)
			(layer "B.Fab")
			(hide yes)
			(effects
				(font
					(size 1 1)
					(thickness 0.15)
				)
				(justify mirror)
			)
		)
		(property "Tolerance" "1%"
			(at 0 0 90)
			(unlocked yes)
			(layer "B.Fab")
			(hide yes)
			(effects
				(font
					(size 1 1)
					(thickness 0.15)
				)
				(justify mirror)
			)
		)
		(sheetname "/Compute module/")
		(sheetfile "compute-module.kicad_sch")
		(attr smd)
		(fp_rect
			(start -0.925 0.47)
			(end 0.925 -0.47)
			(stroke
				(width 0.05)
				(type default)
			)
			(fill no)
			(layer "B.CrtYd")
		)
		(fp_rect
			(start -0.5 0.25)
			(end 0.5 -0.25)
			(stroke
				(width 0.15)
				(type solid)
			)
			(fill no)
			(layer "B.Fab")
		)
		(fp_text user "Author: Antmicro"
			(at -0.95 -4.169 270)
			(layer "B.Fab")
			(effects
				(font
					(size 0.7 0.7)
					(thickness 0.15)
				)
				(justify left bottom mirror)
			)
		)
		(fp_text user "License: Apache-2.0"
			(at -0.95 -5.169 270)
			(layer "B.Fab")
			(effects
				(font
					(size 0.7 0.7)
					(thickness 0.15)
				)
				(justify left bottom mirror)
			)
		)
		(fp_text user "${REFERENCE}"
			(at -0.95 -3.168 270)
			(layer "B.Fab")
			(effects
				(font
					(size 0.7 0.7)
					(thickness 0.15)
				)
				(justify left bottom mirror)
			)
		)
		(pad "1" smd roundrect
			(at -0.48 0 90)
			(size 0.59 0.64)
			(layers "B.Cu" "B.Mask" "B.Paste")
			(roundrect_rratio 0.25)
			(net 3 "GND")
			(pintype "passive")
		)
		(pad "2" smd roundrect
			(at 0.48 0 90)
			(size 0.59 0.64)
			(layers "B.Cu" "B.Mask" "B.Paste")
			(roundrect_rratio 0.25)
			(net 18 "V_{IO}")
			(pintype "passive")
		)
	)
	(footprint "antmicro-footprints:SOIC-8_3.9x4.9x1.75mm_P1.27mm"
		(layer "B.Cu")
		(at 120.523 176.276 180)
		(property "Reference" "U802"
			(at -1.727 2.846 0)
			(layer "B.SilkS")
			(effects
				(font
					(size 0.7 0.7)
					(thickness 0.15)
				)
				(justify left bottom mirror)
			)
		)
		(property "Value" "DS1338_SOIC"
			(at 0 -3.65 0)
			(layer "B.Fab")
			(effects
				(font
					(size 0.7 0.7)
					(thickness 0.15)
				)
				(justify left bottom mirror)
			)
		)
		(property "Datasheet" "https://www.analog.com/media/en/technical-documentation/data-sheets/DS1338-DS1338Z.pdf"
			(at 0 0 0)
			(layer "B.Fab")
			(hide yes)
			(effects
				(font
					(size 1.27 1.27)
					(thickness 0.15)
				)
				(justify mirror)
			)
		)
		(property "Description" "Real-time clock/calendar,  1.71V-5.5V supply, I2C, SOIC-8"
			(at 0 0 0)
			(layer "B.Fab")
			(hide yes)
			(effects
				(font
					(size 1.27 1.27)
					(thickness 0.15)
				)
				(justify mirror)
			)
		)
		(property "MPN" "DS1338Z-18+"
			(at 0 0 180)
			(unlocked yes)
			(layer "B.Fab")
			(hide yes)
			(effects
				(font
					(size 1 1)
					(thickness 0.15)
				)
				(justify mirror)
			)
		)
		(property "Manufacturer" "Maxim Integrated Products"
			(at 0 0 180)
			(unlocked yes)
			(layer "B.Fab")
			(hide yes)
			(effects
				(font
					(size 1 1)
					(thickness 0.15)
				)
				(justify mirror)
			)
		)
		(property "Author" "Antmicro"
			(at 0 0 180)
			(unlocked yes)
			(layer "B.Fab")
			(hide yes)
			(effects
				(font
					(size 1 1)
					(thickness 0.15)
				)
				(justify mirror)
			)
		)
		(property "License" "Apache-2.0"
			(at 0 0 180)
			(unlocked yes)
			(layer "B.Fab")
			(hide yes)
			(effects
				(font
					(size 1 1)
					(thickness 0.15)
				)
				(justify mirror)
			)
		)
		(sheetname "/Peripherals/")
		(sheetfile "peripherals.kicad_sch")
		(attr smd)
		(fp_line
			(start -1.95 2.452)
			(end 1.95 2.45)
			(stroke
				(width 0.15)
				(type solid)
			)
			(layer "B.SilkS")
		)
		(fp_line
			(start -1.95 -2.45)
			(end 1.95 -2.45)
			(stroke
				(width 0.15)
				(type solid)
			)
			(layer "B.SilkS")
		)
		(fp_circle
			(center -2.4 2.45)
			(end -2.35 2.4)
			(stroke
				(width 0.15)
				(type solid)
			)
			(fill yes)
			(layer "B.SilkS")
		)
		(fp_rect
			(start -3.625 2.7)
			(end 3.625 -2.7)
			(stroke
				(width 0.05)
				(type solid)
			)
			(fill no)
			(layer "B.CrtYd")
		)
		(fp_line
			(start 1.949 2.452)
			(end 1.949 -2.45)
			(stroke
				(width 0.15)
				(type solid)
			)
			(layer "B.Fab")
		)
		(fp_line
			(start 1.949 -2.45)
			(end -1.95 -2.45)
			(stroke
				(width 0.15)
				(type solid)
			)
			(layer "B.Fab")
		)
		(fp_line
			(start -0.683 2.452)
			(end 1.949 2.452)
			(stroke
				(width 0.15)
				(type solid)
			)
			(layer "B.Fab")
		)
		(fp_line
			(start -1.95 1.18)
			(end -0.683 2.452)
			(stroke
				(width 0.15)
				(type solid)
			)
			(layer "B.Fab")
		)
		(fp_line
			(start -1.95 -2.45)
			(end -1.95 1.18)
			(stroke
				(width 0.15)
				(type solid)
			)
			(layer "B.Fab")
		)
		(fp_text user "${REFERENCE}"
			(at -3.476 -7.099 0)
			(layer "B.Fab")
			(effects
				(font
					(size 0.7 0.7)
					(thickness 0.15)
				)
				(justify left bottom mirror)
			)
		)
		(fp_text user "Author: Antmicro"
			(at -3.476 -6.099 0)
			(layer "B.Fab")
			(effects
				(font
					(size 0.7 0.7)
					(thickness 0.15)
				)
				(justify left bottom mirror)
			)
		)
		(fp_text user "License: Apache-2.0"
			(at -3.476 -5.099 0)
			(layer "B.Fab")
			(effects
				(font
					(size 0.7 0.7)
					(thickness 0.15)
				)
				(justify left bottom mirror)
			)
		)
		(pad "1" smd roundrect
			(at -2.714 1.905 90)
			(size 0.65 1.525)
			(layers "B.Cu" "B.Mask" "B.Paste")
			(roundrect_rratio 0.25)
			(net 505 "Net-(U802-X1)")
			(pinfunction "X1")
			(pintype "input")
		)
		(pad "2" smd roundrect
			(at -2.714 0.635 90)
			(size 0.65 1.525)
			(layers "B.Cu" "B.Mask" "B.Paste")
			(roundrect_rratio 0.25)
			(net 506 "Net-(U802-X2)")
			(pinfunction "X2")
			(pintype "output")
		)
		(pad "3" smd roundrect
			(at -2.714 -0.632 90)
			(size 0.65 1.525)
			(layers "B.Cu" "B.Mask" "B.Paste")
			(roundrect_rratio 0.25)
			(net 503 "Net-(D811-C)")
			(pinfunction "V_{bat}")
			(pintype "power_in")
		)
		(pad "4" smd roundrect
			(at -2.714 -1.902 90)
			(size 0.65 1.525)
			(layers "B.Cu" "B.Mask" "B.Paste")
			(roundrect_rratio 0.25)
			(net 3 "GND")
			(pinfunction "GND")
			(pintype "power_in")
		)
		(pad "5" smd roundrect
			(at 2.712 -1.902 90)
			(size 0.65 1.525)
			(layers "B.Cu" "B.Mask" "B.Paste")
			(roundrect_rratio 0.25)
			(net 143 "/CSI/I_{2}C1.SDA")
			(pinfunction "SDA")
			(pintype "bidirectional")
		)
		(pad "6" smd roundrect
			(at 2.712 -0.632 90)
			(size 0.65 1.525)
			(layers "B.Cu" "B.Mask" "B.Paste")
			(roundrect_rratio 0.25)
			(net 142 "/CSI/I_{2}C1.SCL")
			(pinfunction "SCL")
			(pintype "input")
		)
		(pad "7" smd roundrect
			(at 2.712 0.635 90)
			(size 0.65 1.525)
			(layers "B.Cu" "B.Mask" "B.Paste")
			(roundrect_rratio 0.25)
			(net 504 "unconnected-(U802-SQW{slash}OUT-Pad7)")
			(pinfunction "SQW/OUT")
			(pintype "output+no_connect")
		)
		(pad "8" smd roundrect
			(at 2.712 1.905 90)
			(size 0.65 1.525)
			(layers "B.Cu" "B.Mask" "B.Paste")
			(roundrect_rratio 0.25)
			(net 9 "+3V3")
			(pinfunction "V_{CC}")
			(pintype "power_in")
		)
	)
	(footprint "antmicro-footprints:R_0402_1005Metric"
		(layer "B.Cu")
		(at 52.487962 153.2565 180)
		(descr "Resistor SMD 0402")
		(tags "resistor SMD 0402")
		(property "Reference" "R313"
			(at -2.04 1.78 0)
			(layer "B.SilkS")
			(effects
				(font
					(size 0.7 0.7)
					(thickness 0.15)
				)
				(justify left bottom mirror)
			)
		)
		(property "Value" "R_33k_0402"
			(at -1.011843 -1.772047 0)
			(layer "B.Fab")
			(effects
				(font
					(size 0.7 0.7)
					(thickness 0.15)
				)
				(justify left bottom mirror)
			)
		)
		(property "Datasheet" "https://www.bourns.com/docs/product-datasheets/cr.pdf"
			(at 0 0 180)
			(layer "B.Fab")
			(hide yes)
			(effects
				(font
					(size 1.27 1.27)
					(thickness 0.15)
				)
			)
		)
		(property "MPN" "CR0402-FX-3302GLF"
			(at 0 0 180)
			(unlocked yes)
			(layer "B.Fab")
			(hide yes)
			(effects
				(font
					(size 1 1)
					(thickness 0.15)
				)
				(justify mirror)
			)
		)
		(property "Manufacturer" "Bourns"
			(at 0 0 180)
			(unlocked yes)
			(layer "B.Fab")
			(hide yes)
			(effects
				(font
					(size 1 1)
					(thickness 0.15)
				)
				(justify mirror)
			)
		)
		(property "License" "Apache-2.0"
			(at 0 0 180)
			(unlocked yes)
			(layer "B.Fab")
			(hide yes)
			(effects
				(font
					(size 1 1)
					(thickness 0.15)
				)
				(justify mirror)
			)
		)
		(property "Author" "Antmicro"
			(at 0 0 180)
			(unlocked yes)
			(layer "B.Fab")
			(hide yes)
			(effects
				(font
					(size 1 1)
					(thickness 0.15)
				)
				(justify mirror)
			)
		)
		(property "Val" "33k"
			(at 0 0 180)
			(unlocked yes)
			(layer "B.Fab")
			(hide yes)
			(effects
				(font
					(size 1 1)
					(thickness 0.15)
				)
				(justify mirror)
			)
		)
		(property "Tolerance" "1%"
			(at 0 0 180)
			(unlocked yes)
			(layer "B.Fab")
			(hide yes)
			(effects
				(font
					(size 1 1)
					(thickness 0.15)
				)
				(justify mirror)
			)
		)
		(sheetname "/Supply/")
		(sheetfile "supply.kicad_sch")
		(attr smd)
		(fp_rect
			(start -0.925 0.47)
			(end 0.925 -0.47)
			(stroke
				(width 0.05)
				(type default)
			)
			(fill no)
			(layer "B.CrtYd")
		)
		(fp_rect
			(start -0.5 0.25)
			(end 0.5 -0.25)
			(stroke
				(width 0.15)
				(type solid)
			)
			(fill no)
			(layer "B.Fab")
		)
		(fp_text user "License: Apache-2.0"
			(at -0.95 -5.169 0)
			(layer "B.Fab")
			(effects
				(font
					(size 0.7 0.7)
					(thickness 0.15)
				)
				(justify left bottom mirror)
			)
		)
		(fp_text user "Author: Antmicro"
			(at -0.95 -4.169 0)
			(layer "B.Fab")
			(effects
				(font
					(size 0.7 0.7)
					(thickness 0.15)
				)
				(justify left bottom mirror)
			)
		)
		(fp_text user "${REFERENCE}"
			(at -0.95 -3.168 0)
			(layer "B.Fab")
			(effects
				(font
					(size 0.7 0.7)
					(thickness 0.15)
				)
				(justify left bottom mirror)
			)
		)
		(pad "1" smd roundrect
			(at -0.48 0 180)
			(size 0.59 0.64)
			(layers "B.Cu" "B.Mask" "B.Paste")
			(roundrect_rratio 0.25)
			(net 351 "/Supply/EN_5V")
			(pintype "passive")
		)
		(pad "2" smd roundrect
			(at 0.48 0 180)
			(size 0.59 0.64)
			(layers "B.Cu" "B.Mask" "B.Paste")
			(roundrect_rratio 0.25)
			(net 43 "VCC")
			(pintype "passive")
		)
	)
)
